(kicad_pcb
	(version 20260206)
	(generator "pcbnew")
	(generator_version "10.0")
	(general
		(thickness 1.6)
		(legacy_teardrops no)
	)
	(paper "A4")
	(title_block
		(title "12092022_DA0F0TMDCD0_F0T_Management_Board_D_brd_V3_OCP.brd")
		(comment 1 "Grand Teton / footprints 1117-1122 of 1440")
	)
	(layers
		(0 "F.Cu" signal "TOP")
		(4 "In1.Cu" signal "GND")
		(6 "In2.Cu" signal "IN1")
		(8 "In3.Cu" signal "GND1")
		(10 "In4.Cu" signal "IN2")
		(12 "In5.Cu" signal "VCC")
		(14 "In6.Cu" signal "VCC1")
		(16 "In7.Cu" signal "IN3")
		(18 "In8.Cu" signal "GND2")
		(20 "In9.Cu" signal "IN4")
		(22 "In10.Cu" signal "GND3")
		(2 "B.Cu" signal "BOTTOM")
		(9 "F.Adhes" user "F.Adhesive")
		(11 "B.Adhes" user "B.Adhesive")
		(13 "F.Paste" user "Package Geometry/Pastemask Top")
		(15 "B.Paste" user "Package Geometry/Pastemask Bottom")
		(5 "F.SilkS" user "Ref Des/Silkscreen Top")
		(7 "B.SilkS" user "Ref Des/Silkscreen Bottom")
		(1 "F.Mask" user "Board Geometry/Soldermask Top")
		(3 "B.Mask" user "Board Geometry/Soldermask Bottom")
		(17 "Dwgs.User" user "User.Drawings")
		(19 "Cmts.User" user "User.Comments")
		(21 "Eco1.User" user "User.Eco1")
		(23 "Eco2.User" user "User.Eco2")
		(25 "Edge.Cuts" user "Board Geometry/Outline")
		(27 "Margin" user)
		(31 "F.CrtYd" user "Package Geometry/Place Bound Top")
		(29 "B.CrtYd" user "Package Geometry/Place Bound Bottom")
		(35 "F.Fab" user "Ref Des/Assembly Top")
		(33 "B.Fab" user "Ref Des/Assembly Bottom")
	)
	(footprint ""
		(layer "B.Cu")
		(at 29.468826 -92.106242)
		(property "Reference" "R519"
			(at 0 0 0)
			(layer "B.SilkS")
			(hide yes)
			(effects
				(font
					(size 1.27 1.27)
				)
				(justify mirror)
			)
		)
		(property "Value" ""
			(at 0 0 0)
			(layer "B.Fab")
			(effects
				(font
					(size 1.27 1.27)
				)
				(justify mirror)
			)
		)
		(duplicate_pad_numbers_are_jumpers no)
		(fp_line
			(start -0.7874 -0.4064)
			(end -0.7874 0.4064)
			(stroke
				(width 0.1524)
				(type default)
			)
			(layer "B.SilkS")
		)
		(fp_line
			(start -0.7874 0.4064)
			(end 0.7874 0.4064)
			(stroke
				(width 0.1524)
				(type default)
			)
			(layer "B.SilkS")
		)
		(fp_line
			(start 0.7874 -0.4064)
			(end -0.7874 -0.4064)
			(stroke
				(width 0.1524)
				(type default)
			)
			(layer "B.SilkS")
		)
		(fp_line
			(start 0.7874 0.4064)
			(end 0.7874 -0.4064)
			(stroke
				(width 0.1524)
				(type default)
			)
			(layer "B.SilkS")
		)
		(fp_line
			(start -0.67945 -0.3048)
			(end -0.67945 0.3048)
			(stroke
				(width 0.1)
				(type default)
			)
			(layer "B.Fab")
		)
		(fp_line
			(start -0.67945 0.3048)
			(end -0.120396 0.3048)
			(stroke
				(width 0.1)
				(type default)
			)
			(layer "B.Fab")
		)
		(fp_line
			(start -0.12065 -0.3048)
			(end -0.67945 -0.3048)
			(stroke
				(width 0.1)
				(type default)
			)
			(layer "B.Fab")
		)
		(fp_line
			(start -0.12065 -0.2794)
			(end -0.12065 -0.3048)
			(stroke
				(width 0.1)
				(type default)
			)
			(layer "B.Fab")
		)
		(fp_line
			(start -0.120396 0.2794)
			(end 0.12065 0.2794)
			(stroke
				(width 0.1)
				(type default)
			)
			(layer "B.Fab")
		)
		(fp_line
			(start -0.120396 0.3048)
			(end -0.120396 0.2794)
			(stroke
				(width 0.1)
				(type default)
			)
			(layer "B.Fab")
		)
		(fp_line
			(start 0.12065 -0.305054)
			(end 0.12065 -0.2794)
			(stroke
				(width 0.1)
				(type default)
			)
			(layer "B.Fab")
		)
		(fp_line
			(start 0.12065 -0.2794)
			(end -0.12065 -0.2794)
			(stroke
				(width 0.1)
				(type default)
			)
			(layer "B.Fab")
		)
		(fp_line
			(start 0.12065 0.2794)
			(end 0.12065 0.3048)
			(stroke
				(width 0.1)
				(type default)
			)
			(layer "B.Fab")
		)
		(fp_line
			(start 0.12065 0.3048)
			(end 0.67945 0.3048)
			(stroke
				(width 0.1)
				(type default)
			)
			(layer "B.Fab")
		)
		(fp_line
			(start 0.67945 -0.305054)
			(end 0.12065 -0.305054)
			(stroke
				(width 0.1)
				(type default)
			)
			(layer "B.Fab")
		)
		(fp_line
			(start 0.67945 0.3048)
			(end 0.67945 -0.305054)
			(stroke
				(width 0.1)
				(type default)
			)
			(layer "B.Fab")
		)
		(pad "1" smd circle
			(at 0.40005 0 180)
			(size 0 0)
			(layers "B.Cu" "B.Mask" "B.Paste")
			(net "BMC_CPLD_GPIO_2")
		)
		(pad "2" smd circle
			(at -0.40005 0 180)
			(size 0 0)
			(layers "B.Cu" "B.Mask" "B.Paste")
			(net "BMC_CPLD_GPIO_2_R2")
		)
	)
	(footprint ""
		(layer "B.Cu")
		(at 41.913302 -63.756794 -90)
		(property "Reference" "R197"
			(at 0 0 90)
			(layer "B.SilkS")
			(hide yes)
			(effects
				(font
					(size 1.27 1.27)
				)
				(justify mirror)
			)
		)
		(property "Value" ""
			(at 0 0 90)
			(layer "B.Fab")
			(effects
				(font
					(size 1.27 1.27)
				)
				(justify mirror)
			)
		)
		(duplicate_pad_numbers_are_jumpers no)
		(fp_line
			(start -0.7874 0.4064)
			(end 0.7874 0.4064)
			(stroke
				(width 0.1524)
				(type default)
			)
			(layer "B.SilkS")
		)
		(fp_line
			(start 0.7874 0.4064)
			(end 0.7874 -0.4064)
			(stroke
				(width 0.1524)
				(type default)
			)
			(layer "B.SilkS")
		)
		(fp_line
			(start -0.7874 -0.4064)
			(end -0.7874 0.4064)
			(stroke
				(width 0.1524)
				(type default)
			)
			(layer "B.SilkS")
		)
		(fp_line
			(start 0.7874 -0.4064)
			(end -0.7874 -0.4064)
			(stroke
				(width 0.1524)
				(type default)
			)
			(layer "B.SilkS")
		)
		(fp_line
			(start -0.67945 0.3048)
			(end -0.120396 0.3048)
			(stroke
				(width 0.1)
				(type default)
			)
			(layer "B.Fab")
		)
		(fp_line
			(start -0.120396 0.3048)
			(end -0.120396 0.2794)
			(stroke
				(width 0.1)
				(type default)
			)
			(layer "B.Fab")
		)
		(fp_line
			(start 0.12065 0.3048)
			(end 0.67945 0.3048)
			(stroke
				(width 0.1)
				(type default)
			)
			(layer "B.Fab")
		)
		(fp_line
			(start 0.67945 0.3048)
			(end 0.67945 -0.305054)
			(stroke
				(width 0.1)
				(type default)
			)
			(layer "B.Fab")
		)
		(fp_line
			(start -0.120396 0.2794)
			(end 0.12065 0.2794)
			(stroke
				(width 0.1)
				(type default)
			)
			(layer "B.Fab")
		)
		(fp_line
			(start 0.12065 0.2794)
			(end 0.12065 0.3048)
			(stroke
				(width 0.1)
				(type default)
			)
			(layer "B.Fab")
		)
		(fp_line
			(start -0.12065 -0.2794)
			(end -0.12065 -0.3048)
			(stroke
				(width 0.1)
				(type default)
			)
			(layer "B.Fab")
		)
		(fp_line
			(start 0.12065 -0.2794)
			(end -0.12065 -0.2794)
			(stroke
				(width 0.1)
				(type default)
			)
			(layer "B.Fab")
		)
		(fp_line
			(start -0.67945 -0.3048)
			(end -0.67945 0.3048)
			(stroke
				(width 0.1)
				(type default)
			)
			(layer "B.Fab")
		)
		(fp_line
			(start -0.12065 -0.3048)
			(end -0.67945 -0.3048)
			(stroke
				(width 0.1)
				(type default)
			)
			(layer "B.Fab")
		)
		(fp_line
			(start 0.12065 -0.305054)
			(end 0.12065 -0.2794)
			(stroke
				(width 0.1)
				(type default)
			)
			(layer "B.Fab")
		)
		(fp_line
			(start 0.67945 -0.305054)
			(end 0.12065 -0.305054)
			(stroke
				(width 0.1)
				(type default)
			)
			(layer "B.Fab")
		)
		(pad "1" smd circle
			(at 0.40005 0 90)
			(size 0 0)
			(layers "B.Cu" "B.Mask" "B.Paste")
			(net "P1V2_P1V0_I3C_VDDL1")
		)
		(pad "2" smd circle
			(at -0.40005 0 90)
			(size 0 0)
			(layers "B.Cu" "B.Mask" "B.Paste")
			(net "I3C4_SPD_SDA")
		)
	)
	(footprint ""
		(layer "B.Cu")
		(at 63.014098 -28.356306 -90)
		(property "Reference" "R256"
			(at 0 0 90)
			(layer "B.SilkS")
			(hide yes)
			(effects
				(font
					(size 1.27 1.27)
				)
				(justify mirror)
			)
		)
		(property "Value" ""
			(at 0 0 90)
			(layer "B.Fab")
			(effects
				(font
					(size 1.27 1.27)
				)
				(justify mirror)
			)
		)
		(duplicate_pad_numbers_are_jumpers no)
		(fp_line
			(start -0.7874 0.4064)
			(end 0.7874 0.4064)
			(stroke
				(width 0.1524)
				(type default)
			)
			(layer "B.SilkS")
		)
		(fp_line
			(start 0.7874 0.4064)
			(end 0.7874 -0.4064)
			(stroke
				(width 0.1524)
				(type default)
			)
			(layer "B.SilkS")
		)
		(fp_line
			(start -0.7874 -0.4064)
			(end -0.7874 0.4064)
			(stroke
				(width 0.1524)
				(type default)
			)
			(layer "B.SilkS")
		)
		(fp_line
			(start 0.7874 -0.4064)
			(end -0.7874 -0.4064)
			(stroke
				(width 0.1524)
				(type default)
			)
			(layer "B.SilkS")
		)
		(fp_line
			(start -0.67945 0.3048)
			(end -0.120396 0.3048)
			(stroke
				(width 0.1)
				(type default)
			)
			(layer "B.Fab")
		)
		(fp_line
			(start -0.120396 0.3048)
			(end -0.120396 0.2794)
			(stroke
				(width 0.1)
				(type default)
			)
			(layer "B.Fab")
		)
		(fp_line
			(start 0.12065 0.3048)
			(end 0.67945 0.3048)
			(stroke
				(width 0.1)
				(type default)
			)
			(layer "B.Fab")
		)
		(fp_line
			(start 0.67945 0.3048)
			(end 0.67945 -0.305054)
			(stroke
				(width 0.1)
				(type default)
			)
			(layer "B.Fab")
		)
		(fp_line
			(start -0.120396 0.2794)
			(end 0.12065 0.2794)
			(stroke
				(width 0.1)
				(type default)
			)
			(layer "B.Fab")
		)
		(fp_line
			(start 0.12065 0.2794)
			(end 0.12065 0.3048)
			(stroke
				(width 0.1)
				(type default)
			)
			(layer "B.Fab")
		)
		(fp_line
			(start -0.12065 -0.2794)
			(end -0.12065 -0.3048)
			(stroke
				(width 0.1)
				(type default)
			)
			(layer "B.Fab")
		)
		(fp_line
			(start 0.12065 -0.2794)
			(end -0.12065 -0.2794)
			(stroke
				(width 0.1)
				(type default)
			)
			(layer "B.Fab")
		)
		(fp_line
			(start -0.67945 -0.3048)
			(end -0.67945 0.3048)
			(stroke
				(width 0.1)
				(type default)
			)
			(layer "B.Fab")
		)
		(fp_line
			(start -0.12065 -0.3048)
			(end -0.67945 -0.3048)
			(stroke
				(width 0.1)
				(type default)
			)
			(layer "B.Fab")
		)
		(fp_line
			(start 0.12065 -0.305054)
			(end 0.12065 -0.2794)
			(stroke
				(width 0.1)
				(type default)
			)
			(layer "B.Fab")
		)
		(fp_line
			(start 0.67945 -0.305054)
			(end 0.12065 -0.305054)
			(stroke
				(width 0.1)
				(type default)
			)
			(layer "B.Fab")
		)
		(pad "1" smd circle
			(at 0.40005 0 90)
			(size 0 0)
			(layers "B.Cu" "B.Mask" "B.Paste")
			(net "P3V3_AUX")
		)
		(pad "2" smd circle
			(at -0.40005 0 90)
			(size 0 0)
			(layers "B.Cu" "B.Mask" "B.Paste")
			(net "SMB_BMC_MM7_R_SCL")
		)
	)
	(footprint ""
		(layer "B.Cu")
		(at 60.452 -27.87904)
		(property "Reference" "R253"
			(at 0 0 0)
			(layer "B.SilkS")
			(hide yes)
			(effects
				(font
					(size 1.27 1.27)
				)
				(justify mirror)
			)
		)
		(property "Value" ""
			(at 0 0 0)
			(layer "B.Fab")
			(effects
				(font
					(size 1.27 1.27)
				)
				(justify mirror)
			)
		)
		(duplicate_pad_numbers_are_jumpers no)
		(fp_line
			(start -0.7874 -0.4064)
			(end -0.7874 0.4064)
			(stroke
				(width 0.1524)
				(type default)
			)
			(layer "B.SilkS")
		)
		(fp_line
			(start -0.7874 0.4064)
			(end 0.7874 0.4064)
			(stroke
				(width 0.1524)
				(type default)
			)
			(layer "B.SilkS")
		)
		(fp_line
			(start 0.7874 -0.4064)
			(end -0.7874 -0.4064)
			(stroke
				(width 0.1524)
				(type default)
			)
			(layer "B.SilkS")
		)
		(fp_line
			(start 0.7874 0.4064)
			(end 0.7874 -0.4064)
			(stroke
				(width 0.1524)
				(type default)
			)
			(layer "B.SilkS")
		)
		(fp_line
			(start -0.67945 -0.3048)
			(end -0.67945 0.3048)
			(stroke
				(width 0.1)
				(type default)
			)
			(layer "B.Fab")
		)
		(fp_line
			(start -0.67945 0.3048)
			(end -0.120396 0.3048)
			(stroke
				(width 0.1)
				(type default)
			)
			(layer "B.Fab")
		)
		(fp_line
			(start -0.12065 -0.3048)
			(end -0.67945 -0.3048)
			(stroke
				(width 0.1)
				(type default)
			)
			(layer "B.Fab")
		)
		(fp_line
			(start -0.12065 -0.2794)
			(end -0.12065 -0.3048)
			(stroke
				(width 0.1)
				(type default)
			)
			(layer "B.Fab")
		)
		(fp_line
			(start -0.120396 0.2794)
			(end 0.12065 0.2794)
			(stroke
				(width 0.1)
				(type default)
			)
			(layer "B.Fab")
		)
		(fp_line
			(start -0.120396 0.3048)
			(end -0.120396 0.2794)
			(stroke
				(width 0.1)
				(type default)
			)
			(layer "B.Fab")
		)
		(fp_line
			(start 0.12065 -0.305054)
			(end 0.12065 -0.2794)
			(stroke
				(width 0.1)
				(type default)
			)
			(layer "B.Fab")
		)
		(fp_line
			(start 0.12065 -0.2794)
			(end -0.12065 -0.2794)
			(stroke
				(width 0.1)
				(type default)
			)
			(layer "B.Fab")
		)
		(fp_line
			(start 0.12065 0.2794)
			(end 0.12065 0.3048)
			(stroke
				(width 0.1)
				(type default)
			)
			(layer "B.Fab")
		)
		(fp_line
			(start 0.12065 0.3048)
			(end 0.67945 0.3048)
			(stroke
				(width 0.1)
				(type default)
			)
			(layer "B.Fab")
		)
		(fp_line
			(start 0.67945 -0.305054)
			(end 0.12065 -0.305054)
			(stroke
				(width 0.1)
				(type default)
			)
			(layer "B.Fab")
		)
		(fp_line
			(start 0.67945 0.3048)
			(end 0.67945 -0.305054)
			(stroke
				(width 0.1)
				(type default)
			)
			(layer "B.Fab")
		)
		(pad "1" smd circle
			(at 0.40005 0 180)
			(size 0 0)
			(layers "B.Cu" "B.Mask" "B.Paste")
			(net "P3V3_AUX")
		)
		(pad "2" smd circle
			(at -0.40005 0 180)
			(size 0 0)
			(layers "B.Cu" "B.Mask" "B.Paste")
			(net "SMB_BMC_MM5_R_SDA")
		)
	)
	(footprint ""
		(layer "B.Cu")
		(at 49.784 -28.829 -90)
		(property "Reference" "R880"
			(at 0 0 90)
			(layer "B.SilkS")
			(hide yes)
			(effects
				(font
					(size 1.27 1.27)
				)
				(justify mirror)
			)
		)
		(property "Value" ""
			(at 0 0 90)
			(layer "B.Fab")
			(effects
				(font
					(size 1.27 1.27)
				)
				(justify mirror)
			)
		)
		(duplicate_pad_numbers_are_jumpers no)
		(fp_line
			(start -0.7874 0.4064)
			(end 0.7874 0.4064)
			(stroke
				(width 0.1524)
				(type default)
			)
			(layer "B.SilkS")
		)
		(fp_line
			(start 0.7874 0.4064)
			(end 0.7874 -0.4064)
			(stroke
				(width 0.1524)
				(type default)
			)
			(layer "B.SilkS")
		)
		(fp_line
			(start -0.7874 -0.4064)
			(end -0.7874 0.4064)
			(stroke
				(width 0.1524)
				(type default)
			)
			(layer "B.SilkS")
		)
		(fp_line
			(start 0.7874 -0.4064)
			(end -0.7874 -0.4064)
			(stroke
				(width 0.1524)
				(type default)
			)
			(layer "B.SilkS")
		)
		(fp_line
			(start -0.67945 0.3048)
			(end -0.120396 0.3048)
			(stroke
				(width 0.1)
				(type default)
			)
			(layer "B.Fab")
		)
		(fp_line
			(start -0.120396 0.3048)
			(end -0.120396 0.2794)
			(stroke
				(width 0.1)
				(type default)
			)
			(layer "B.Fab")
		)
		(fp_line
			(start 0.12065 0.3048)
			(end 0.67945 0.3048)
			(stroke
				(width 0.1)
				(type default)
			)
			(layer "B.Fab")
		)
		(fp_line
			(start 0.67945 0.3048)
			(end 0.67945 -0.305054)
			(stroke
				(width 0.1)
				(type default)
			)
			(layer "B.Fab")
		)
		(fp_line
			(start -0.120396 0.2794)
			(end 0.12065 0.2794)
			(stroke
				(width 0.1)
				(type default)
			)
			(layer "B.Fab")
		)
		(fp_line
			(start 0.12065 0.2794)
			(end 0.12065 0.3048)
			(stroke
				(width 0.1)
				(type default)
			)
			(layer "B.Fab")
		)
		(fp_line
			(start -0.12065 -0.2794)
			(end -0.12065 -0.3048)
			(stroke
				(width 0.1)
				(type default)
			)
			(layer "B.Fab")
		)
		(fp_line
			(start 0.12065 -0.2794)
			(end -0.12065 -0.2794)
			(stroke
				(width 0.1)
				(type default)
			)
			(layer "B.Fab")
		)
		(fp_line
			(start -0.67945 -0.3048)
			(end -0.67945 0.3048)
			(stroke
				(width 0.1)
				(type default)
			)
			(layer "B.Fab")
		)
		(fp_line
			(start -0.12065 -0.3048)
			(end -0.67945 -0.3048)
			(stroke
				(width 0.1)
				(type default)
			)
			(layer "B.Fab")
		)
		(fp_line
			(start 0.12065 -0.305054)
			(end 0.12065 -0.2794)
			(stroke
				(width 0.1)
				(type default)
			)
			(layer "B.Fab")
		)
		(fp_line
			(start 0.67945 -0.305054)
			(end 0.12065 -0.305054)
			(stroke
				(width 0.1)
				(type default)
			)
			(layer "B.Fab")
		)
		(pad "1" smd circle
			(at 0.40005 0 90)
			(size 0 0)
			(layers "B.Cu" "B.Mask" "B.Paste")
			(net "SMB_BMC_MM16_R5_SDA")
		)
		(pad "2" smd circle
			(at -0.40005 0 90)
			(size 0 0)
			(layers "B.Cu" "B.Mask" "B.Paste")
			(net "SMB_BMC_MM16_SDA")
		)
	)
	(footprint ""
		(layer "B.Cu")
		(at 40.62222 -60.35294 -90)
		(property "Reference" "R462"
			(at 0 0 90)
			(layer "B.SilkS")
			(hide yes)
			(effects
				(font
					(size 1.27 1.27)
				)
				(justify mirror)
			)
		)
		(property "Value" ""
			(at 0 0 90)
			(layer "B.Fab")
			(effects
				(font
					(size 1.27 1.27)
				)
				(justify mirror)
			)
		)
		(duplicate_pad_numbers_are_jumpers no)
		(fp_line
			(start -0.7874 0.4064)
			(end 0.7874 0.4064)
			(stroke
				(width 0.1524)
				(type default)
			)
			(layer "B.SilkS")
		)
		(fp_line
			(start 0.7874 0.4064)
			(end 0.7874 -0.4064)
			(stroke
				(width 0.1524)
				(type default)
			)
			(layer "B.SilkS")
		)
		(fp_line
			(start -0.7874 -0.4064)
			(end -0.7874 0.4064)
			(stroke
				(width 0.1524)
				(type default)
			)
			(layer "B.SilkS")
		)
		(fp_line
			(start 0.7874 -0.4064)
			(end -0.7874 -0.4064)
			(stroke
				(width 0.1524)
				(type default)
			)
			(layer "B.SilkS")
		)
		(fp_line
			(start -0.67945 0.3048)
			(end -0.120396 0.3048)
			(stroke
				(width 0.1)
				(type default)
			)
			(layer "B.Fab")
		)
		(fp_line
			(start -0.120396 0.3048)
			(end -0.120396 0.2794)
			(stroke
				(width 0.1)
				(type default)
			)
			(layer "B.Fab")
		)
		(fp_line
			(start 0.12065 0.3048)
			(end 0.67945 0.3048)
			(stroke
				(width 0.1)
				(type default)
			)
			(layer "B.Fab")
		)
		(fp_line
			(start 0.67945 0.3048)
			(end 0.67945 -0.305054)
			(stroke
				(width 0.1)
				(type default)
			)
			(layer "B.Fab")
		)
		(fp_line
			(start -0.120396 0.2794)
			(end 0.12065 0.2794)
			(stroke
				(width 0.1)
				(type default)
			)
			(layer "B.Fab")
		)
		(fp_line
			(start 0.12065 0.2794)
			(end 0.12065 0.3048)
			(stroke
				(width 0.1)
				(type default)
			)
			(layer "B.Fab")
		)
		(fp_line
			(start -0.12065 -0.2794)
			(end -0.12065 -0.3048)
			(stroke
				(width 0.1)
				(type default)
			)
			(layer "B.Fab")
		)
		(fp_line
			(start 0.12065 -0.2794)
			(end -0.12065 -0.2794)
			(stroke
				(width 0.1)
				(type default)
			)
			(layer "B.Fab")
		)
		(fp_line
			(start -0.67945 -0.3048)
			(end -0.67945 0.3048)
			(stroke
				(width 0.1)
				(type default)
			)
			(layer "B.Fab")
		)
		(fp_line
			(start -0.12065 -0.3048)
			(end -0.67945 -0.3048)
			(stroke
				(width 0.1)
				(type default)
			)
			(layer "B.Fab")
		)
		(fp_line
			(start 0.12065 -0.305054)
			(end 0.12065 -0.2794)
			(stroke
				(width 0.1)
				(type default)
			)
			(layer "B.Fab")
		)
		(fp_line
			(start 0.67945 -0.305054)
			(end 0.12065 -0.305054)
			(stroke
				(width 0.1)
				(type default)
			)
			(layer "B.Fab")
		)
		(pad "1" smd circle
			(at 0.40005 0 90)
			(size 0 0)
			(layers "B.Cu" "B.Mask" "B.Paste")
			(net "P3V3_AUX")
		)
		(pad "2" smd circle
			(at -0.40005 0 90)
			(size 0 0)
			(layers "B.Cu" "B.Mask" "B.Paste")
			(net "SYS_BMC_PWRBTN_R1_N")
		)
	)
)
